(kicad_pcb
	(version 20260206)
	(generator "pcbnew")
	(generator_version "10.0")
	(general
		(thickness 1.6)
		(legacy_teardrops no)
	)
	(paper "A4")
	(title_block
		(title "Wiwynn_Tioga_Pass_MB.brd")
		(comment 1 "Tioga Pass / footprints 3485-3492 of 4770")
	)
	(layers
		(0 "F.Cu" signal "TOP")
		(4 "In1.Cu" signal "L2GND")
		(6 "In2.Cu" signal "L3")
		(8 "In3.Cu" signal "L4GND")
		(10 "In4.Cu" signal "L5")
		(12 "In5.Cu" signal "L6GND")
		(14 "In6.Cu" signal "L7VCC")
		(16 "In7.Cu" signal "L8VCC")
		(18 "In8.Cu" signal "L9GND")
		(20 "In9.Cu" signal "L10")
		(22 "In10.Cu" signal "L11GND")
		(24 "In11.Cu" signal "L12")
		(26 "In12.Cu" signal "L13GND")
		(2 "B.Cu" signal "BOTTOM")
		(9 "F.Adhes" user "F.Adhesive")
		(11 "B.Adhes" user "B.Adhesive")
		(13 "F.Paste" user "Package Geometry/Pastemask Top")
		(15 "B.Paste" user "Package Geometry/Pastemask Bottom")
		(5 "F.SilkS" user "Ref Des/Silkscreen Top")
		(7 "B.SilkS" user "Ref Des/Silkscreen Bottom")
		(1 "F.Mask" user "Board Geometry/Soldermask Top")
		(3 "B.Mask" user "Board Geometry/Soldermask Bottom")
		(17 "Dwgs.User" user "User.Drawings")
		(19 "Cmts.User" user "User.Comments")
		(21 "Eco1.User" user "User.Eco1")
		(23 "Eco2.User" user "User.Eco2")
		(25 "Edge.Cuts" user "Board Geometry/Outline")
		(27 "Margin" user)
		(31 "F.CrtYd" user "Package Geometry/Place Bound Top")
		(29 "B.CrtYd" user "Package Geometry/Place Bound Bottom")
		(35 "F.Fab" user "Ref Des/Assembly Top")
		(33 "B.Fab" user "Ref Des/Assembly Bottom")
	)
	(footprint ""
		(layer "B.Cu")
		(at 282.259024 -73.492614 -90)
		(property "Reference" "R4P8"
			(at 0 0 90)
			(layer "B.SilkS")
			(hide yes)
			(effects
				(font
					(size 1.27 1.27)
				)
				(justify mirror)
			)
		)
		(property "Value" ""
			(at 0 0 90)
			(layer "B.Fab")
			(effects
				(font
					(size 1.27 1.27)
				)
				(justify mirror)
			)
		)
		(duplicate_pad_numbers_are_jumpers no)
		(fp_rect
			(start 0.2794 0.9906)
			(end -0.2794 -0.1016)
			(stroke
				(width 0)
				(type default)
			)
			(fill no)
			(layer "B.CrtYd")
		)
		(fp_line
			(start -0.2794 0.9906)
			(end -0.2794 -0.1016)
			(stroke
				(width 0.1)
				(type default)
			)
			(layer "B.Fab")
		)
		(fp_line
			(start 0.2794 0.9906)
			(end -0.2794 0.9906)
			(stroke
				(width 0.1)
				(type default)
			)
			(layer "B.Fab")
		)
		(fp_line
			(start -0.2794 -0.1016)
			(end 0.2794 -0.1016)
			(stroke
				(width 0.1)
				(type default)
			)
			(layer "B.Fab")
		)
		(fp_line
			(start 0.2794 -0.1016)
			(end 0.2794 0.9906)
			(stroke
				(width 0.1)
				(type default)
			)
			(layer "B.Fab")
		)
		(pad "1" smd rect
			(at 0 0 90)
			(size 0.508 0.508)
			(layers "B.Cu" "B.Mask" "B.Paste")
			(net "A_CPU0_ABC_RCOMP0")
		)
		(pad "2" smd rect
			(at 0 0.889 90)
			(size 0.508 0.508)
			(layers "B.Cu" "B.Mask" "B.Paste")
			(net "GND")
		)
		(zone
			(layer "B.Cu")
			(hatch none 0.5)
			(connect_pads
				(clearance 0)
			)
			(min_thickness 0.25)
			(keepout
				(tracks allowed)
				(vias not_allowed)
				(pads allowed)
				(copperpour not_allowed)
				(footprints allowed)
			)
			(placement
				(enabled no)
				(sheetname "")
			)
			(fill
				(thermal_gap 0.5)
				(thermal_bridge_width 0.5)
				(island_removal_mode 0)
			)
			(polygon
				(pts
					(xy 281.624024 -73.238614) (xy 282.005024 -73.238614) (xy 282.005024 -73.746614) (xy 281.624024 -73.746614)
				)
			)
		)
		(zone
			(layer "B.Cu")
			(hatch none 0.5)
			(connect_pads
				(clearance 0)
			)
			(min_thickness 0.25)
			(keepout
				(tracks not_allowed)
				(vias allowed)
				(pads allowed)
				(copperpour not_allowed)
				(footprints allowed)
			)
			(placement
				(enabled no)
				(sheetname "")
			)
			(fill
				(thermal_gap 0.5)
				(thermal_bridge_width 0.5)
				(island_removal_mode 0)
			)
			(polygon
				(pts
					(xy 281.624024 -73.238614) (xy 282.005024 -73.238614) (xy 282.005024 -73.746614) (xy 281.624024 -73.746614)
				)
			)
		)
	)
	(footprint ""
		(layer "B.Cu")
		(at 175.006 -88.646 180)
		(property "Reference" "R6N8"
			(at 0 0 0)
			(layer "B.SilkS")
			(hide yes)
			(effects
				(font
					(size 1.27 1.27)
				)
				(justify mirror)
			)
		)
		(property "Value" ""
			(at 0 0 0)
			(layer "B.Fab")
			(effects
				(font
					(size 1.27 1.27)
				)
				(justify mirror)
			)
		)
		(duplicate_pad_numbers_are_jumpers no)
		(fp_poly
			(pts
				(xy 0.2794 -0.1016) (xy -0.2794 -0.1016) (xy -0.2794 0.9906) (xy 0.2794 0.9906)
			)
			(stroke
				(width 0)
				(type default)
			)
			(fill no)
			(layer "B.CrtYd")
		)
		(fp_line
			(start 0.2794 0.9906)
			(end -0.2794 0.9906)
			(stroke
				(width 0.1)
				(type default)
			)
			(layer "B.Fab")
		)
		(fp_line
			(start 0.2794 -0.1016)
			(end 0.2794 0.9906)
			(stroke
				(width 0.1)
				(type default)
			)
			(layer "B.Fab")
		)
		(fp_line
			(start -0.2794 0.9906)
			(end -0.2794 -0.1016)
			(stroke
				(width 0.1)
				(type default)
			)
			(layer "B.Fab")
		)
		(fp_line
			(start -0.2794 -0.1016)
			(end 0.2794 -0.1016)
			(stroke
				(width 0.1)
				(type default)
			)
			(layer "B.Fab")
		)
		(pad "1" smd rect
			(at 0 0)
			(size 0.508 0.508)
			(layers "B.Cu" "B.Mask" "B.Paste")
			(net "SMB_CPU1_PE_HP_GTL_SCL")
		)
		(pad "2" smd rect
			(at 0 0.889)
			(size 0.508 0.508)
			(layers "B.Cu" "B.Mask" "B.Paste")
			(net "SMB_CPU1_PE_HP_GTL_R_SCL")
		)
		(zone
			(layer "B.Cu")
			(hatch none 0.5)
			(connect_pads
				(clearance 0)
			)
			(min_thickness 0.25)
			(keepout
				(tracks not_allowed)
				(vias allowed)
				(pads allowed)
				(copperpour not_allowed)
				(footprints allowed)
			)
			(placement
				(enabled no)
				(sheetname "")
			)
			(fill
				(thermal_gap 0.5)
				(thermal_bridge_width 0.5)
				(island_removal_mode 0)
			)
			(polygon
				(pts
					(xy 174.752 -89.281) (xy 175.26 -89.281) (xy 175.26 -88.9) (xy 174.752 -88.9)
				)
			)
		)
		(zone
			(layer "B.Cu")
			(hatch none 0.5)
			(connect_pads
				(clearance 0)
			)
			(min_thickness 0.25)
			(keepout
				(tracks allowed)
				(vias not_allowed)
				(pads allowed)
				(copperpour not_allowed)
				(footprints allowed)
			)
			(placement
				(enabled no)
				(sheetname "")
			)
			(fill
				(thermal_gap 0.5)
				(thermal_bridge_width 0.5)
				(island_removal_mode 0)
			)
			(polygon
				(pts
					(xy 174.752 -88.9) (xy 175.26 -88.9) (xy 175.26 -89.281) (xy 174.752 -89.281)
				)
			)
		)
	)
	(footprint ""
		(layer "B.Cu")
		(at 113.702592 -71.714614 180)
		(property "Reference" "C7P17"
			(at 0 0 0)
			(layer "B.SilkS")
			(hide yes)
			(effects
				(font
					(size 1.27 1.27)
				)
				(justify mirror)
			)
		)
		(property "Value" ""
			(at 0 0 0)
			(layer "B.Fab")
			(effects
				(font
					(size 1.27 1.27)
				)
				(justify mirror)
			)
		)
		(duplicate_pad_numbers_are_jumpers no)
		(fp_poly
			(pts
				(xy 0.7239 -0.2159) (xy -0.7239 -0.2159) (xy -0.7239 1.9939) (xy 0.7239 1.9939)
			)
			(stroke
				(width 0)
				(type default)
			)
			(fill no)
			(layer "B.CrtYd")
		)
		(fp_line
			(start 0.7239 1.9939)
			(end -0.7239 1.9939)
			(stroke
				(width 0.1)
				(type default)
			)
			(layer "B.Fab")
		)
		(fp_line
			(start 0.7239 -0.2159)
			(end 0.7239 1.9939)
			(stroke
				(width 0.1)
				(type default)
			)
			(layer "B.Fab")
		)
		(fp_line
			(start -0.7239 1.9939)
			(end -0.7239 -0.2159)
			(stroke
				(width 0.1)
				(type default)
			)
			(layer "B.Fab")
		)
		(fp_line
			(start -0.7239 -0.2159)
			(end 0.7239 -0.2159)
			(stroke
				(width 0.1)
				(type default)
			)
			(layer "B.Fab")
		)
		(pad "1" smd rect
			(at 0 0)
			(size 1.27 1.016)
			(layers "B.Cu" "B.Mask" "B.Paste")
			(net "PVCCIO_CPU1")
		)
		(pad "2" smd rect
			(at 0 1.778)
			(size 1.27 1.016)
			(layers "B.Cu" "B.Mask" "B.Paste")
			(net "GND")
		)
		(zone
			(layer "B.Cu")
			(hatch none 0.5)
			(connect_pads
				(clearance 0)
			)
			(min_thickness 0.25)
			(keepout
				(tracks not_allowed)
				(vias allowed)
				(pads allowed)
				(copperpour not_allowed)
				(footprints allowed)
			)
			(placement
				(enabled no)
				(sheetname "")
			)
			(fill
				(thermal_gap 0.5)
				(thermal_bridge_width 0.5)
				(island_removal_mode 0)
			)
			(polygon
				(pts
					(xy 113.067592 -72.222614) (xy 114.337592 -72.222614) (xy 114.337592 -72.984614) (xy 113.067592 -72.984614)
				)
			)
		)
	)
	(footprint ""
		(layer "B.Cu")
		(at 477.645222 -3.3782 -90)
		(property "Reference" "C9G9"
			(at 0 0 90)
			(layer "B.SilkS")
			(hide yes)
			(effects
				(font
					(size 1.27 1.27)
				)
				(justify mirror)
			)
		)
		(property "Value" ""
			(at 0 0 90)
			(layer "B.Fab")
			(effects
				(font
					(size 1.27 1.27)
				)
				(justify mirror)
			)
		)
		(duplicate_pad_numbers_are_jumpers no)
		(fp_poly
			(pts
				(xy -0.3048 -0.1016) (xy -0.3048 0.9906) (xy 0.3048 0.9906) (xy 0.3048 -0.1016)
			)
			(stroke
				(width 0)
				(type default)
			)
			(fill no)
			(layer "B.CrtYd")
		)
		(fp_line
			(start -0.3048 0.9906)
			(end -0.3048 -0.1016)
			(stroke
				(width 0.1)
				(type default)
			)
			(layer "B.Fab")
		)
		(fp_line
			(start 0.3048 0.9906)
			(end -0.3048 0.9906)
			(stroke
				(width 0.1)
				(type default)
			)
			(layer "B.Fab")
		)
		(fp_line
			(start -0.3048 -0.1016)
			(end 0.3048 -0.1016)
			(stroke
				(width 0.1)
				(type default)
			)
			(layer "B.Fab")
		)
		(fp_line
			(start 0.3048 -0.1016)
			(end 0.3048 0.9906)
			(stroke
				(width 0.1)
				(type default)
			)
			(layer "B.Fab")
		)
		(pad "1" smd rect
			(at 0 0 90)
			(size 0.508 0.508)
			(layers "B.Cu" "B.Mask" "B.Paste")
			(net "NIC_SER_P_MDI_3_DP")
		)
		(pad "2" smd rect
			(at 0 0.889 90)
			(size 0.508 0.508)
			(layers "B.Cu" "B.Mask" "B.Paste")
			(net "NIC_MDI_MNG_RX_DP")
		)
		(zone
			(layer "B.Cu")
			(hatch none 0.5)
			(connect_pads
				(clearance 0)
			)
			(min_thickness 0.25)
			(keepout
				(tracks not_allowed)
				(vias allowed)
				(pads allowed)
				(copperpour not_allowed)
				(footprints allowed)
			)
			(placement
				(enabled no)
				(sheetname "")
			)
			(fill
				(thermal_gap 0.5)
				(thermal_bridge_width 0.5)
				(island_removal_mode 0)
			)
			(polygon
				(pts
					(xy 477.010222 -3.1242) (xy 477.010222 -3.6322) (xy 477.391222 -3.6322) (xy 477.391222 -3.1242)
				)
			)
		)
		(zone
			(layer "B.Cu")
			(hatch none 0.5)
			(connect_pads
				(clearance 0)
			)
			(min_thickness 0.25)
			(keepout
				(tracks allowed)
				(vias not_allowed)
				(pads allowed)
				(copperpour not_allowed)
				(footprints allowed)
			)
			(placement
				(enabled no)
				(sheetname "")
			)
			(fill
				(thermal_gap 0.5)
				(thermal_bridge_width 0.5)
				(island_removal_mode 0)
			)
			(polygon
				(pts
					(xy 477.391222 -3.1242) (xy 477.391222 -3.6322) (xy 477.010222 -3.6322) (xy 477.010222 -3.1242)
				)
			)
		)
	)
	(footprint ""
		(layer "B.Cu")
		(at 494.712244 -47.503588 180)
		(property "Reference" "R25W133"
			(at 0.8382 -0.67818 180)
			(unlocked yes)
			(layer "B.SilkS")
			(effects
				(font
					(size 0.4064 0.254)
					(thickness 0.1524)
				)
				(justify left mirror)
			)
		)
		(property "Value" ""
			(at 0 0 0)
			(layer "B.Fab")
			(effects
				(font
					(size 1.27 1.27)
				)
				(justify mirror)
			)
		)
		(duplicate_pad_numbers_are_jumpers no)
		(fp_poly
			(pts
				(xy 0.2794 -0.1016) (xy -0.2794 -0.1016) (xy -0.2794 0.9906) (xy 0.2794 0.9906)
			)
			(stroke
				(width 0)
				(type default)
			)
			(fill no)
			(layer "B.CrtYd")
		)
		(fp_line
			(start 0.2794 0.9906)
			(end -0.2794 0.9906)
			(stroke
				(width 0.1)
				(type default)
			)
			(layer "B.Fab")
		)
		(fp_line
			(start 0.2794 -0.1016)
			(end 0.2794 0.9906)
			(stroke
				(width 0.1)
				(type default)
			)
			(layer "B.Fab")
		)
		(fp_line
			(start -0.2794 0.9906)
			(end -0.2794 -0.1016)
			(stroke
				(width 0.1)
				(type default)
			)
			(layer "B.Fab")
		)
		(fp_line
			(start -0.2794 -0.1016)
			(end 0.2794 -0.1016)
			(stroke
				(width 0.1)
				(type default)
			)
			(layer "B.Fab")
		)
		(pad "1" smd rect
			(at 0 0)
			(size 0.508 0.508)
			(layers "B.Cu" "B.Mask" "B.Paste")
			(net "I2C_BMC_VGA_DDC_SCL_G")
		)
		(pad "2" smd rect
			(at 0 0.889)
			(size 0.508 0.508)
			(layers "B.Cu" "B.Mask" "B.Paste")
			(net "V_IBMC_5V_DDC_SCL_J")
		)
		(zone
			(layer "B.Cu")
			(hatch none 0.5)
			(connect_pads
				(clearance 0)
			)
			(min_thickness 0.25)
			(keepout
				(tracks not_allowed)
				(vias allowed)
				(pads allowed)
				(copperpour not_allowed)
				(footprints allowed)
			)
			(placement
				(enabled no)
				(sheetname "")
			)
			(fill
				(thermal_gap 0.5)
				(thermal_bridge_width 0.5)
				(island_removal_mode 0)
			)
			(polygon
				(pts
					(xy 494.458244 -48.138588) (xy 494.966244 -48.138588) (xy 494.966244 -47.757588) (xy 494.458244 -47.757588)
				)
			)
		)
		(zone
			(layer "B.Cu")
			(hatch none 0.5)
			(connect_pads
				(clearance 0)
			)
			(min_thickness 0.25)
			(keepout
				(tracks allowed)
				(vias not_allowed)
				(pads allowed)
				(copperpour not_allowed)
				(footprints allowed)
			)
			(placement
				(enabled no)
				(sheetname "")
			)
			(fill
				(thermal_gap 0.5)
				(thermal_bridge_width 0.5)
				(island_removal_mode 0)
			)
			(polygon
				(pts
					(xy 494.458244 -47.757588) (xy 494.966244 -47.757588) (xy 494.966244 -48.138588) (xy 494.458244 -48.138588)
				)
			)
		)
	)
	(footprint ""
		(layer "B.Cu")
		(at 404.101046 -25.600152 180)
		(property "Reference" "R1U39"
			(at 0 0 0)
			(layer "B.SilkS")
			(hide yes)
			(effects
				(font
					(size 1.27 1.27)
				)
				(justify mirror)
			)
		)
		(property "Value" ""
			(at 0 0 0)
			(layer "B.Fab")
			(effects
				(font
					(size 1.27 1.27)
				)
				(justify mirror)
			)
		)
		(duplicate_pad_numbers_are_jumpers no)
		(fp_poly
			(pts
				(xy 0.2794 -0.1016) (xy -0.2794 -0.1016) (xy -0.2794 0.9906) (xy 0.2794 0.9906)
			)
			(stroke
				(width 0)
				(type default)
			)
			(fill no)
			(layer "B.CrtYd")
		)
		(fp_line
			(start 0.2794 0.9906)
			(end -0.2794 0.9906)
			(stroke
				(width 0.1)
				(type default)
			)
			(layer "B.Fab")
		)
		(fp_line
			(start 0.2794 -0.1016)
			(end 0.2794 0.9906)
			(stroke
				(width 0.1)
				(type default)
			)
			(layer "B.Fab")
		)
		(fp_line
			(start -0.2794 0.9906)
			(end -0.2794 -0.1016)
			(stroke
				(width 0.1)
				(type default)
			)
			(layer "B.Fab")
		)
		(fp_line
			(start -0.2794 -0.1016)
			(end 0.2794 -0.1016)
			(stroke
				(width 0.1)
				(type default)
			)
			(layer "B.Fab")
		)
		(pad "1" smd rect
			(at 0 0)
			(size 0.508 0.508)
			(layers "B.Cu" "B.Mask" "B.Paste")
			(net "P3V3_STBY")
		)
		(pad "2" smd rect
			(at 0 0.889)
			(size 0.508 0.508)
			(layers "B.Cu" "B.Mask" "B.Paste")
			(net "A_P3V3_STBY_SCALED")
		)
		(zone
			(layer "B.Cu")
			(hatch none 0.5)
			(connect_pads
				(clearance 0)
			)
			(min_thickness 0.25)
			(keepout
				(tracks not_allowed)
				(vias allowed)
				(pads allowed)
				(copperpour not_allowed)
				(footprints allowed)
			)
			(placement
				(enabled no)
				(sheetname "")
			)
			(fill
				(thermal_gap 0.5)
				(thermal_bridge_width 0.5)
				(island_removal_mode 0)
			)
			(polygon
				(pts
					(xy 403.847046 -26.235152) (xy 404.355046 -26.235152) (xy 404.355046 -25.854152) (xy 403.847046 -25.854152)
				)
			)
		)
		(zone
			(layer "B.Cu")
			(hatch none 0.5)
			(connect_pads
				(clearance 0)
			)
			(min_thickness 0.25)
			(keepout
				(tracks allowed)
				(vias not_allowed)
				(pads allowed)
				(copperpour not_allowed)
				(footprints allowed)
			)
			(placement
				(enabled no)
				(sheetname "")
			)
			(fill
				(thermal_gap 0.5)
				(thermal_bridge_width 0.5)
				(island_removal_mode 0)
			)
			(polygon
				(pts
					(xy 403.847046 -25.854152) (xy 404.355046 -25.854152) (xy 404.355046 -26.235152) (xy 403.847046 -26.235152)
				)
			)
		)
	)
	(footprint ""
		(layer "B.Cu")
		(at 409.1432 -123.6218 90)
		(property "Reference" "C2M5"
			(at 0 0 90)
			(layer "B.SilkS")
			(hide yes)
			(effects
				(font
					(size 1.27 1.27)
				)
				(justify mirror)
			)
		)
		(property "Value" ""
			(at 0 0 90)
			(layer "B.Fab")
			(effects
				(font
					(size 1.27 1.27)
				)
				(justify mirror)
			)
		)
		(duplicate_pad_numbers_are_jumpers no)
		(fp_poly
			(pts
				(xy 0.4953 -0.2032) (xy -0.4953 -0.2032) (xy -0.4953 1.6002) (xy 0.4953 1.6002)
			)
			(stroke
				(width 0)
				(type default)
			)
			(fill no)
			(layer "B.CrtYd")
		)
		(fp_line
			(start 0.4953 -0.2032)
			(end -0.4953 -0.2032)
			(stroke
				(width 0.1)
				(type default)
			)
			(layer "B.Fab")
		)
		(fp_line
			(start -0.4953 -0.2032)
			(end -0.4953 1.6002)
			(stroke
				(width 0.1)
				(type default)
			)
			(layer "B.Fab")
		)
		(fp_line
			(start 0.4953 1.6002)
			(end 0.4953 -0.2032)
			(stroke
				(width 0.1)
				(type default)
			)
			(layer "B.Fab")
		)
		(fp_line
			(start -0.4953 1.6002)
			(end 0.4953 1.6002)
			(stroke
				(width 0.1)
				(type default)
			)
			(layer "B.Fab")
		)
		(pad "1" smd rect
			(at 0 0 270)
			(size 0.762 0.889)
			(layers "B.Cu" "B.Mask" "B.Paste")
			(net "P1V05_PCH_STBY_WM20_PLL")
		)
		(pad "2" smd rect
			(at 0 1.397 270)
			(size 0.762 0.889)
			(layers "B.Cu" "B.Mask" "B.Paste")
			(net "GND")
		)
		(zone
			(layer "B.Cu")
			(hatch none 0.5)
			(connect_pads
				(clearance 0)
			)
			(min_thickness 0.25)
			(keepout
				(tracks not_allowed)
				(vias allowed)
				(pads allowed)
				(copperpour not_allowed)
				(footprints allowed)
			)
			(placement
				(enabled no)
				(sheetname "")
			)
			(fill
				(thermal_gap 0.5)
				(thermal_bridge_width 0.5)
				(island_removal_mode 0)
			)
			(polygon
				(pts
					(xy 409.5877 -124.0028) (xy 409.5877 -123.2408) (xy 410.0957 -123.2408) (xy 410.0957 -124.0028)
				)
			)
		)
	)
	(footprint ""
		(layer "B.Cu")
		(at 405.369522 -113.7412)
		(property "Reference" "L2M1"
			(at 0 0 0)
			(layer "B.SilkS")
			(hide yes)
			(effects
				(font
					(size 1.27 1.27)
				)
				(justify mirror)
			)
		)
		(property "Value" ""
			(at 0 0 0)
			(layer "B.Fab")
			(effects
				(font
					(size 1.27 1.27)
				)
				(justify mirror)
			)
		)
		(duplicate_pad_numbers_are_jumpers no)
		(fp_rect
			(start 0.7239 1.93802)
			(end -0.7239 -0.26162)
			(stroke
				(width 0)
				(type default)
			)
			(fill no)
			(layer "B.CrtYd")
		)
		(fp_line
			(start -0.7239 -0.26162)
			(end 0.7239 -0.26162)
			(stroke
				(width 0.1)
				(type default)
			)
			(layer "B.Fab")
		)
		(fp_line
			(start -0.7239 1.93802)
			(end -0.7239 -0.26162)
			(stroke
				(width 0.1)
				(type default)
			)
			(layer "B.Fab")
		)
		(fp_line
			(start 0.7239 -0.26162)
			(end 0.7239 1.93802)
			(stroke
				(width 0.1)
				(type default)
			)
			(layer "B.Fab")
		)
		(fp_line
			(start 0.7239 1.93802)
			(end -0.7239 1.93802)
			(stroke
				(width 0.1)
				(type default)
			)
			(layer "B.Fab")
		)
		(pad "1" smd rect
			(at 0 0 180)
			(size 1.4986 0.9144)
			(layers "B.Cu" "B.Mask" "B.Paste")
			(net "P1V05_PCH_STBY")
		)
		(pad "2" smd rect
			(at 0 1.6764 180)
			(size 1.4986 0.9144)
			(layers "B.Cu" "B.Mask" "B.Paste")
			(net "P1V05_PCH_STBY_KR_PLL")
		)
		(zone
			(layer "B.Cu")
			(hatch none 0.5)
			(connect_pads
				(clearance 0)
			)
			(min_thickness 0.25)
			(keepout
				(tracks allowed)
				(vias not_allowed)
				(pads allowed)
				(copperpour not_allowed)
				(footprints allowed)
			)
			(placement
				(enabled no)
				(sheetname "")
			)
			(fill
				(thermal_gap 0.5)
				(thermal_bridge_width 0.5)
				(island_removal_mode 0)
			)
			(polygon
				(pts
					(xy 406.118822 -113.284) (xy 406.118822 -112.522) (xy 404.620222 -112.522) (xy 404.620222 -113.284)
				)
			)
		)
		(zone
			(layer "B.Cu")
			(hatch none 0.5)
			(connect_pads
				(clearance 0)
			)
			(min_thickness 0.25)
			(keepout
				(tracks not_allowed)
				(vias allowed)
				(pads allowed)
				(copperpour not_allowed)
				(footprints allowed)
			)
			(placement
				(enabled no)
				(sheetname "")
			)
			(fill
				(thermal_gap 0.5)
				(thermal_bridge_width 0.5)
				(island_removal_mode 0)
			)
			(polygon
				(pts
					(xy 406.118822 -112.522) (xy 406.118822 -113.284) (xy 404.620222 -113.284) (xy 404.620222 -112.522)
				)
			)
		)
	)
)
